(kicad_pcb
	(version 20221018)
	(generator pcbnew)
	(general
    (thickness 1.518)
  )
	(paper "A4")
	(title_block
    (title "Kria K26 Devboard")
    (date "2024-03-26")
    (rev "1.2.5")
    (comment 1 "www.antmicro.com")
    (comment 2 "Antmicro Ltd.")
		(comment 9 "footprints 201-208 of 660")
	)
	(layers
    (0 "F.Cu" mixed)
    (1 "In1.Cu" power)
    (2 "In2.Cu" mixed)
    (3 "In3.Cu" power)
    (4 "In4.Cu" mixed)
    (5 "In5.Cu" power)
    (6 "In6.Cu" mixed)
    (31 "B.Cu" power)
    (32 "B.Adhes" user "B.Adhesive")
    (33 "F.Adhes" user "F.Adhesive")
    (34 "B.Paste" user)
    (35 "F.Paste" user)
    (36 "B.SilkS" user "B.Silkscreen")
    (37 "F.SilkS" user "F.Silkscreen")
    (38 "B.Mask" user)
    (39 "F.Mask" user)
    (40 "Dwgs.User" user "User.Drawings")
    (41 "Cmts.User" user "User.Comments")
    (42 "Eco1.User" user "User.Eco1")
    (43 "Eco2.User" user "User.Eco2")
    (44 "Edge.Cuts" user)
    (45 "Margin" user)
    (46 "B.CrtYd" user "B.Courtyard")
    (47 "F.CrtYd" user "F.Courtyard")
    (48 "B.Fab" user)
    (49 "F.Fab" user)
  )
	(footprint "kria-k26-devboard-footprints:Oscillator_SMD_JU6_7x5mm_P2.54mm" (layer "F.Cu")
    (at 102.15 101.95 -90)
    (descr "SMD Crystal Oscillator IDT")
    (tags "SMD SMT crystal oscillator")
    (property "Author" "Antmicro")
    (property "License" "Apache-2.0")
    (property "MPN" "XLL736027.000000X")
    (property "Manufacturer" "Renesas")
    (property "Sheetfile" "clock.kicad_sch")
    (property "Sheetname" "Clock distribution")
    (property "Val" "27 MHz")
    (property "ki_description" "27 MHz XO (Standard) LVDS Oscillator 3.3V Enable/Disable 6-SMD, No Lead")
    (property "ki_keywords" "OSCILLATOR, LVDS")
    (attr smd)
    (fp_text reference "U9" (at 0.46 3.79 -90) (layer "F.SilkS")
        (effects (font (size 0.7 0.7) (thickness 0.15)) (justify left bottom))
    )
    (fp_text value "Oscillator_27MHz_JU6" (at -0.03 4.679 -90) (layer "F.Fab") hide
        (effects (font (size 0.7 0.7) (thickness 0.15)) (justify left bottom))
    )
    (fp_text user "${REFERENCE}" (at -2.61 6.679 -90) (layer "F.Fab") hide
        (effects (font (size 0.7 0.7) (thickness 0.15)) (justify left bottom))
    )
    (fp_text user "Author: Antmicro" (at -2.61 7.679 -90) (layer "F.Fab") hide
        (effects (font (size 0.7 0.7) (thickness 0.15)) (justify left bottom))
    )
    (fp_text user "License: Apache-2.0" (at -2.61 8.679 -90) (layer "F.Fab") hide
        (effects (font (size 0.7 0.7) (thickness 0.15)) (justify left bottom))
    )
    (fp_line (start -2.65 -3.625) (end 2.608 -3.621)
      (stroke (width 0.15) (type solid)) (layer "F.SilkS"))
    (fp_line (start -2.61 -1.101) (end -2.61 -1.44)
      (stroke (width 0.15) (type solid)) (layer "F.SilkS"))
    (fp_line (start -2.61 1.439) (end -2.61 1.1)
      (stroke (width 0.15) (type solid)) (layer "F.SilkS"))
    (fp_line (start 2.608 -1.44) (end 2.608 -1.101)
      (stroke (width 0.15) (type solid)) (layer "F.SilkS"))
    (fp_line (start 2.608 1.1) (end 2.608 1.439)
      (stroke (width 0.15) (type solid)) (layer "F.SilkS"))
    (fp_line (start 2.608 3.62) (end -2.61 3.62)
      (stroke (width 0.15) (type solid)) (layer "F.SilkS"))
    (fp_circle (center -3.15 -3.575) (end -3.1 -3.575)
      (stroke (width 0.15) (type solid)) (fill solid) (layer "F.SilkS"))
    (fp_rect (start -3.375 -3.75) (end 3.375 3.75)
      (stroke (width 0.05) (type solid)) (fill none) (layer "F.CrtYd"))
    (fp_line (start -2.5 -2.5) (end -2.5 3.499)
      (stroke (width 0.15) (type solid)) (layer "F.Fab"))
    (fp_line (start -2.5 3.499) (end 2.499 3.499)
      (stroke (width 0.15) (type solid)) (layer "F.Fab"))
    (fp_line (start -1.5 -3.5) (end -2.5 -2.5)
      (stroke (width 0.15) (type solid)) (layer "F.Fab"))
    (fp_line (start 2.499 -3.5) (end -1.5 -3.5)
      (stroke (width 0.15) (type solid)) (layer "F.Fab"))
    (fp_line (start 2.499 3.499) (end 2.499 -3.5)
      (stroke (width 0.15) (type solid)) (layer "F.Fab"))
    (pad "1" smd roundrect (at -2.101 -2.54 180) (size 1.8 2) (layers "F.Cu" "F.Paste" "F.Mask") (roundrect_rratio 0.25)
      (net 185 "/Clock distribution/PS_CLK_EN") (pinfunction "EN") (pintype "input"))
    (pad "2" smd roundrect (at -2.101 0 180) (size 1.8 2) (layers "F.Cu" "F.Paste" "F.Mask") (roundrect_rratio 0.25)
      (net 709 "unconnected-(U9-NC-Pad2)") (pinfunction "NC") (pintype "no_connect"))
    (pad "3" smd roundrect (at -2.101 2.539 180) (size 1.8 2) (layers "F.Cu" "F.Paste" "F.Mask") (roundrect_rratio 0.25)
      (net 1 "GND") (pinfunction "GND") (pintype "power_in"))
    (pad "4" smd roundrect (at 2.1 2.539 180) (size 1.8 2) (layers "F.Cu" "F.Paste" "F.Mask") (roundrect_rratio 0.25)
      (net 181 "/Clock distribution/GTR_REFCLK0_C2M_P") (pinfunction "OUT+") (pintype "output"))
    (pad "5" smd roundrect (at 2.1 0 180) (size 1.8 2) (layers "F.Cu" "F.Paste" "F.Mask") (roundrect_rratio 0.25)
      (net 182 "/Clock distribution/GTR_REFCLK0_C2M_N") (pinfunction "OUT-") (pintype "output"))
    (pad "6" smd roundrect (at 2.1 -2.54 180) (size 1.8 2) (layers "F.Cu" "F.Paste" "F.Mask") (roundrect_rratio 0.25)
      (net 15 "PS_3V3") (pinfunction "VCC") (pintype "power_in"))
  )
	(footprint "kria-k26-devboard-footprints:R_0603_1608Metric" (layer "F.Cu")
    (at 187.25 76.55 180)
    (descr "Resistor SMD 0603")
    (tags "resistor SMD 0603")
    (property "Author" "Antmicro")
    (property "License" "Apache-2.0")
    (property "MPN" "CR0603-FX-63R4ELF")
    (property "Manufacturer" "Bourns")
    (property "Sheetfile" "PoE.kicad_sch")
    (property "Sheetname" "PoE")
    (property "Tolerance" "1%")
    (property "Val" "63R4")
    (property "ki_description" "63R4 resistor in 0603 package with 1% tolerance")
    (attr smd)
    (fp_text reference "R116" (at 1.4 0.78 180) (layer "F.SilkS")
        (effects (font (size 0.7 0.7) (thickness 0.15)) (justify left bottom))
    )
    (fp_text value "R_63R4_0603" (at 0 1.6 180) (layer "F.Fab") hide
        (effects (font (size 0.7 0.7) (thickness 0.15)) (justify left bottom))
    )
    (fp_text user "Author: Antmicro" (at -1.25 4.9 180) (layer "F.Fab") hide
        (effects (font (size 0.7 0.7) (thickness 0.15)) (justify left bottom))
    )
    (fp_text user "License: Apache-2.0" (at -1.25 5.9 180) (layer "F.Fab") hide
        (effects (font (size 0.7 0.7) (thickness 0.15)) (justify left bottom))
    )
    (fp_text user "${REFERENCE}" (at -1.25 3.898 180) (layer "F.Fab") hide
        (effects (font (size 0.7 0.7) (thickness 0.15)) (justify left bottom))
    )
    (fp_line (start -0.3 -0.3) (end 0.3 -0.3)
      (stroke (width 0.15) (type solid)) (layer "F.SilkS"))
    (fp_line (start -0.3 0.3) (end 0.3 0.3)
      (stroke (width 0.15) (type solid)) (layer "F.SilkS"))
    (fp_rect (start -1.25 -0.7) (end 1.25 0.7)
      (stroke (width 0.05) (type solid)) (fill none) (layer "F.CrtYd"))
    (fp_rect (start -0.8 -0.4) (end 0.8 0.4)
      (stroke (width 0.15) (type solid)) (fill none) (layer "F.Fab"))
    (pad "1" smd roundrect (at -0.7 0 180) (size 0.6 0.8) (layers "F.Cu" "F.Paste" "F.Mask") (roundrect_rratio 0.2)
      (net 342 "Net-(IC1-CLS)") (pintype "passive"))
    (pad "2" smd roundrect (at 0.7 0 180) (size 0.6 0.8) (layers "F.Cu" "F.Paste" "F.Mask") (roundrect_rratio 0.2)
      (net 10 "/Power Supply/PoE/VSS_POE_IN") (pintype "passive"))
  )
	(footprint "kria-k26-devboard-footprints:C_0402_1005Metric" (layer "F.Cu")
    (at 189.85 67.6)
    (descr "Capacitor SMD 0402")
    (tags "capacitor SMD 0402")
    (property "Author" "Antmicro")
    (property "Dielectric" "X5R")
    (property "License" "Apache-2.0")
    (property "MPN" "GRM155R61H104KE14D")
    (property "Manufacturer" "Murata")
    (property "Sheetfile" "supply-oring.kicad_sch")
    (property "Sheetname" "Supply ORing")
    (property "Val" "100n")
    (property "Voltage" "50V")
    (property "ki_description" " ")
    (attr smd)
    (fp_text reference "C230" (at -3.6 0.35) (layer "F.SilkS")
        (effects (font (size 0.7 0.7) (thickness 0.15)) (justify left bottom))
    )
    (fp_text value "C_100n_0402" (at 0 1.4) (layer "F.Fab") hide
        (effects (font (size 0.7 0.7) (thickness 0.15)) (justify left bottom))
    )
    (fp_text user "License: Apache-2.0" (at -0.932 5.17) (layer "F.Fab") hide
        (effects (font (size 0.7 0.7) (thickness 0.15)) (justify left bottom))
    )
    (fp_text user "${REFERENCE}" (at -0.932 3.168) (layer "F.Fab") hide
        (effects (font (size 0.7 0.7) (thickness 0.15)) (justify left bottom))
    )
    (fp_text user "Author: Antmicro" (at -0.932 4.17) (layer "F.Fab") hide
        (effects (font (size 0.7 0.7) (thickness 0.15)) (justify left bottom))
    )
    (fp_rect (start -0.94 -0.47) (end 0.94 0.47)
      (stroke (width 0.05) (type solid)) (fill none) (layer "F.CrtYd"))
    (fp_rect (start -0.499 -0.249) (end 0.499 0.249)
      (stroke (width 0.15) (type solid)) (fill none) (layer "F.Fab"))
    (pad "1" smd roundrect (at -0.484 0) (size 0.59 0.64) (layers "F.Cu" "F.Paste" "F.Mask") (roundrect_rratio 0.25)
      (net 14 "/Power Supply/DC/DC conventers/DC_MAIN_BUS") (pintype "passive"))
    (pad "2" smd roundrect (at 0.484 0) (size 0.59 0.64) (layers "F.Cu" "F.Paste" "F.Mask") (roundrect_rratio 0.25)
      (net 331 "Net-(U58-GND)") (pintype "passive"))
  )
	(footprint "kria-k26-devboard-footprints:D_SOD-323F" (layer "F.Cu")
    (at 189.9 69.15 180)
    (property "Author" "Antmicro")
    (property "License" "Apache-2.0")
    (property "MPN" "1N4148WS")
    (property "Manufacturer" "ON Semiconductor")
    (property "Sheetfile" "supply-oring.kicad_sch")
    (property "Sheetname" "Supply ORing")
    (property "ki_description" "Small Signal Fast Switching Diode")
    (attr smd)
    (fp_text reference "D22" (at 1.12 -1.69 180) (layer "F.SilkS")
        (effects (font (size 0.7 0.7) (thickness 0.15)) (justify left bottom))
    )
    (fp_text value "1N4148WS" (at -1.7 1.9 180) (layer "F.Fab") hide
        (effects (font (size 0.7 0.7) (thickness 0.15)) (justify left bottom))
    )
    (fp_text user "${REFERENCE}" (at -1.8 3.2 180) (layer "F.Fab") hide
        (effects (font (size 0.7 0.7) (thickness 0.15)) (justify left bottom))
    )
    (fp_text user "License: Apache-2.0" (at -1.8 5.8 180) (layer "F.Fab") hide
        (effects (font (size 0.7 0.7) (thickness 0.15)) (justify left bottom))
    )
    (fp_text user "Author: Antmicro" (at -1.8 4.46 180) (layer "F.Fab") hide
        (effects (font (size 0.7 0.7) (thickness 0.15)) (justify left bottom))
    )
    (fp_line (start -0.975 -0.75) (end -0.975 -0.45)
      (stroke (width 0.15) (type solid)) (layer "F.SilkS"))
    (fp_line (start -0.975 0.748) (end -0.975 0.45)
      (stroke (width 0.15) (type solid)) (layer "F.SilkS"))
    (fp_line (start -0.625 -0.75) (end -0.975 -0.75)
      (stroke (width 0.15) (type solid)) (layer "F.SilkS"))
    (fp_line (start -0.625 0.748) (end -0.975 0.748)
      (stroke (width 0.15) (type solid)) (layer "F.SilkS"))
    (fp_line (start -0.5 -0.426) (end -0.5 0.424)
      (stroke (width 0.15) (type solid)) (layer "F.SilkS"))
    (fp_line (start 0.623 -0.75) (end 0.973 -0.75)
      (stroke (width 0.15) (type solid)) (layer "F.SilkS"))
    (fp_line (start 0.973 -0.75) (end 0.973 -0.45)
      (stroke (width 0.15) (type solid)) (layer "F.SilkS"))
    (fp_line (start 0.973 0.45) (end 0.973 0.748)
      (stroke (width 0.15) (type solid)) (layer "F.SilkS"))
    (fp_line (start 0.973 0.748) (end 0.623 0.748)
      (stroke (width 0.15) (type solid)) (layer "F.SilkS"))
    (fp_rect (start -1.6 -0.827) (end 1.599 0.825)
      (stroke (width 0.05) (type solid)) (fill none) (layer "F.CrtYd"))
    (fp_line (start -0.85 -0.625) (end 0.848 -0.625)
      (stroke (width 0.15) (type solid)) (layer "F.Fab"))
    (fp_line (start -0.85 0.623) (end -0.85 -0.625)
      (stroke (width 0.15) (type solid)) (layer "F.Fab"))
    (fp_line (start -0.85 0.623) (end 0.848 0.623)
      (stroke (width 0.15) (type solid)) (layer "F.Fab"))
    (fp_line (start 0.848 -0.625) (end 0.848 0.623)
      (stroke (width 0.15) (type solid)) (layer "F.Fab"))
    (pad "A" smd roundrect (at 1.05 0 180) (size 0.8 0.6) (layers "F.Cu" "F.Paste" "F.Mask") (roundrect_rratio 0.15)
      (net 331 "Net-(U58-GND)") (pinfunction "A") (pintype "passive"))
    (pad "K" smd roundrect (at -1.051 0 180) (size 0.8 0.6) (layers "F.Cu" "F.Paste" "F.Mask") (roundrect_rratio 0.15)
      (net 1 "GND") (pinfunction "K") (pintype "passive"))
  )
	(footprint "kria-k26-devboard-footprints:TP_SMD_0.75mm" (layer "F.Cu")
    (at 105.08 147.12)
    (property "Author" "Antmicro")
    (property "License" "Apache-2.0")
    (property "MPN" "")
    (property "Manufacturer" "")
    (property "Sheetfile" "reset.kicad_sch")
    (property "Sheetname" "Reset logic")
    (property "ki_description" "Test Point 0.75mm")
    (attr exclude_from_pos_files)
    (fp_text reference "TP14" (at -2.19 -0.51) (layer "F.SilkS")
        (effects (font (size 0.7 0.7) (thickness 0.15)) (justify left bottom))
    )
    (fp_text value "TP_0.75mm_SMD" (at 0 1.2) (layer "F.Fab") hide
        (effects (font (size 0.7 0.7) (thickness 0.15)) (justify left bottom))
    )
    (fp_text user "License: Apache-2.0" (at -0.4 5.101) (layer "F.Fab") hide
        (effects (font (size 0.7 0.7) (thickness 0.15)) (justify left bottom))
    )
    (fp_text user "Author: Antmicro" (at -0.4 3.901) (layer "F.Fab") hide
        (effects (font (size 0.7 0.7) (thickness 0.15)) (justify left bottom))
    )
    (fp_text user "${REFERENCE}" (at -0.4 2.7) (layer "F.Fab") hide
        (effects (font (size 0.7 0.7) (thickness 0.15)) (justify left bottom))
    )
    (pad "1" smd circle (at 0 0) (size 0.75 0.75) (layers "F.Cu" "F.Mask")
      (net 161 "/Reset logic/PS_RST") (pinfunction "1") (pintype "passive"))
  )
	(footprint "kria-k26-devboard-footprints:TP_SMD_0.75mm" (layer "F.Cu")
    (at 99.7 147.16)
    (property "Author" "Antmicro")
    (property "License" "Apache-2.0")
    (property "MPN" "")
    (property "Manufacturer" "")
    (property "Sheetfile" "reset.kicad_sch")
    (property "Sheetname" "Reset logic")
    (property "ki_description" "Test Point 0.75mm")
    (attr exclude_from_pos_files)
    (fp_text reference "TP15" (at -1.15 -0.49) (layer "F.SilkS")
        (effects (font (size 0.7 0.7) (thickness 0.15)) (justify left bottom))
    )
    (fp_text value "TP_0.75mm_SMD" (at 0 1.2) (layer "F.Fab") hide
        (effects (font (size 0.7 0.7) (thickness 0.15)) (justify left bottom))
    )
    (fp_text user "Author: Antmicro" (at -0.4 3.901) (layer "F.Fab") hide
        (effects (font (size 0.7 0.7) (thickness 0.15)) (justify left bottom))
    )
    (fp_text user "${REFERENCE}" (at -0.4 2.7) (layer "F.Fab") hide
        (effects (font (size 0.7 0.7) (thickness 0.15)) (justify left bottom))
    )
    (fp_text user "License: Apache-2.0" (at -0.4 5.101) (layer "F.Fab") hide
        (effects (font (size 0.7 0.7) (thickness 0.15)) (justify left bottom))
    )
    (pad "1" smd circle (at 0 0) (size 0.75 0.75) (layers "F.Cu" "F.Mask")
      (net 174 "/Reset logic/PL_RST") (pinfunction "1") (pintype "passive"))
  )
	(footprint "kria-k26-devboard-footprints:TP_SMD_0.75mm" (layer "F.Cu")
    (at 104.85 117.3)
    (property "Author" "Antmicro")
    (property "License" "Apache-2.0")
    (property "MPN" "")
    (property "Manufacturer" "")
    (property "Sheetfile" "reset.kicad_sch")
    (property "Sheetname" "Reset logic")
    (property "ki_description" "Test Point 0.75mm")
    (attr exclude_from_pos_files)
    (fp_text reference "TP16" (at -1.24 -0.45) (layer "F.SilkS")
        (effects (font (size 0.7 0.7) (thickness 0.15)) (justify left bottom))
    )
    (fp_text value "TP_0.75mm_SMD" (at 0 1.2) (layer "F.Fab") hide
        (effects (font (size 0.7 0.7) (thickness 0.15)) (justify left bottom))
    )
    (fp_text user "Author: Antmicro" (at -0.4 3.901) (layer "F.Fab") hide
        (effects (font (size 0.7 0.7) (thickness 0.15)) (justify left bottom))
    )
    (fp_text user "${REFERENCE}" (at -0.4 2.7) (layer "F.Fab") hide
        (effects (font (size 0.7 0.7) (thickness 0.15)) (justify left bottom))
    )
    (fp_text user "License: Apache-2.0" (at -0.4 5.101) (layer "F.Fab") hide
        (effects (font (size 0.7 0.7) (thickness 0.15)) (justify left bottom))
    )
    (pad "1" smd circle (at 0 0) (size 0.75 0.75) (layers "F.Cu" "F.Mask")
      (net 185 "/Clock distribution/PS_CLK_EN") (pinfunction "1") (pintype "passive"))
  )
	(footprint "kria-k26-devboard-footprints:R_0402_1005Metric" (layer "F.Cu")
    (at 190.7 64.065 -90)
    (descr "Resistor SMD 0402")
    (tags "resistor SMD 0402")
    (property "Author" "Antmicro")
    (property "License" "Apache-2.0")
    (property "MPN" "CR0402-FX-1000GLF")
    (property "Manufacturer" "Bourns")
    (property "Sheetfile" "supply-oring.kicad_sch")
    (property "Sheetname" "Supply ORing")
    (property "Tolerance" "1%")
    (property "Val" "100R")
    (property "ki_description" "100R resistor in 0402 package with 1% tolerance")
    (attr smd)
    (fp_text reference "R148" (at 0.685 -1.15 -90) (layer "F.SilkS")
        (effects (font (size 0.7 0.7) (thickness 0.15)) (justify left bottom))
    )
    (fp_text value "R_100R_0402" (at 0 1.4 -90) (layer "F.Fab") hide
        (effects (font (size 0.7 0.7) (thickness 0.15)) (justify left bottom))
    )
    (fp_text user "Author: Antmicro" (at -0.95 4.169 -90) (layer "F.Fab") hide
        (effects (font (size 0.7 0.7) (thickness 0.15)) (justify left bottom))
    )
    (fp_text user "${REFERENCE}" (at -0.95 3.168 -90) (layer "F.Fab") hide
        (effects (font (size 0.7 0.7) (thickness 0.15)) (justify left bottom))
    )
    (fp_text user "License: Apache-2.0" (at -0.95 5.169 -90) (layer "F.Fab") hide
        (effects (font (size 0.7 0.7) (thickness 0.15)) (justify left bottom))
    )
    (fp_rect (start -0.93 -0.47) (end 0.93 0.47)
      (stroke (width 0.05) (type solid)) (fill none) (layer "F.CrtYd"))
    (fp_rect (start -0.5 -0.25) (end 0.5 0.25)
      (stroke (width 0.15) (type solid)) (fill none) (layer "F.Fab"))
    (pad "1" smd roundrect (at -0.485 0 270) (size 0.59 0.64) (layers "F.Cu" "F.Paste" "F.Mask") (roundrect_rratio 0.25)
      (net 14 "/Power Supply/DC/DC conventers/DC_MAIN_BUS") (pintype "passive"))
    (pad "2" smd roundrect (at 0.485 0 270) (size 0.59 0.64) (layers "F.Cu" "F.Paste" "F.Mask") (roundrect_rratio 0.25)
      (net 328 "Net-(U58-VDD)") (pintype "passive"))
  )
)
